# T6G (Grand Teton) — schematic netlist excerpt (pin names and nets, part order shuffled) for the footprints in the layout excerpt that follows; sources: Cadence DE-HDL packaged netlist, KiCad conversion of 04192023_DAF0TMB3IC0_F0TG_MB_C_brd_V02_OCP.brd

PJ09_P1_P  Q_SHORT  EMPTY  pkg SM  page 364 : \1\ = P0V9_CPU1_RT_2D ; \2\ = P0V9_RETIMER_CPU1_SENSE_SH_P
C2494  Q_CAP  22UF 4V 20% X6S  pkg C0402  page 74 : A = PVDD11_S3_P1 ; B = GND
R562  Q_RES  2.2K 5% CHIP  pkg 0402LF  page 55 : A = PVDD18_S5_P1 ; B = CPU1_NMI_SYNC_FLOOD_N

(kicad_pcb
	(version 20260206)
	(generator "pcbnew")
	(generator_version "10.0")
	(general
		(thickness 1.6)
		(legacy_teardrops no)
	)
	(paper "A4")
	(title_block
		(title "04192023_DAF0TMB3IC0_F0TG_MB_C_brd_V02_OCP.brd")
		(comment 1 "Grand Teton / footprints 5620-5622 of 8354")
	)
	(layers
		(0 "F.Cu" signal "TOP")
		(4 "In1.Cu" signal "GND")
		(6 "In2.Cu" signal "IN1")
		(8 "In3.Cu" signal "GND1")
		(10 "In4.Cu" signal "IN2")
		(12 "In5.Cu" signal "GND2")
		(14 "In6.Cu" signal "IN3")
		(16 "In7.Cu" signal "GND3")
		(18 "In8.Cu" signal "VCC")
		(20 "In9.Cu" signal "VCC1")
		(22 "In10.Cu" signal "GND4")
		(24 "In11.Cu" signal "IN4")
		(26 "In12.Cu" signal "GND5")
		(28 "In13.Cu" signal "IN5")
		(30 "In14.Cu" signal "GND6")
		(32 "In15.Cu" signal "IN6")
		(34 "In16.Cu" signal "GND7")
		(2 "B.Cu" signal "BOTTOM")
		(9 "F.Adhes" user "F.Adhesive")
		(11 "B.Adhes" user "B.Adhesive")
		(13 "F.Paste" user "Package Geometry/Pastemask Top")
		(15 "B.Paste" user "Package Geometry/Pastemask Bottom")
		(5 "F.SilkS" user "Ref Des/Silkscreen Top")
		(7 "B.SilkS" user "Ref Des/Silkscreen Bottom")
		(1 "F.Mask" user "Board Geometry/Soldermask Top")
		(3 "B.Mask" user "Board Geometry/Soldermask Bottom")
		(17 "Dwgs.User" user "User.Drawings")
		(19 "Cmts.User" user "User.Comments")
		(21 "Eco1.User" user "User.Eco1")
		(23 "Eco2.User" user "User.Eco2")
		(25 "Edge.Cuts" user "Board Geometry/Outline")
		(27 "Margin" user)
		(31 "F.CrtYd" user "Package Geometry/Place Bound Top")
		(29 "B.CrtYd" user "Package Geometry/Place Bound Bottom")
		(35 "F.Fab" user "Ref Des/Assembly Top")
		(33 "B.Fab" user "Ref Des/Assembly Bottom")
	)
	(footprint ""
		(layer "B.Cu")
		(at 108.627164 -261.748016 90)
		(property "Reference" "C2494"
			(at 0 0 90)
			(layer "B.SilkS")
			(hide yes)
			(effects
				(font
					(size 1.27 1.27)
				)
				(justify mirror)
			)
		)
		(property "Value" ""
			(at 0 0 90)
			(layer "B.Fab")
			(effects
				(font
					(size 1.27 1.27)
				)
				(justify mirror)
			)
		)
		(duplicate_pad_numbers_are_jumpers no)
		(fp_line
			(start 0.7874 -0.4064)
			(end -0.7874 -0.4064)
			(stroke
				(width 0.1524)
				(type default)
			)
			(layer "B.SilkS")
		)
		(fp_line
			(start -0.7874 -0.4064)
			(end -0.7874 0.4064)
			(stroke
				(width 0.1524)
				(type default)
			)
			(layer "B.SilkS")
		)
		(fp_line
			(start 0.7874 0.4064)
			(end 0.7874 -0.4064)
			(stroke
				(width 0.1524)
				(type default)
			)
			(layer "B.SilkS")
		)
		(fp_line
			(start -0.7874 0.4064)
			(end 0.7874 0.4064)
			(stroke
				(width 0.1524)
				(type default)
			)
			(layer "B.SilkS")
		)
		(fp_line
			(start 0.67945 -0.305054)
			(end 0.12065 -0.305054)
			(stroke
				(width 0.1)
				(type default)
			)
			(layer "B.Fab")
		)
		(fp_line
			(start 0.12065 -0.305054)
			(end 0.12065 -0.2794)
			(stroke
				(width 0.1)
				(type default)
			)
			(layer "B.Fab")
		)
		(fp_line
			(start -0.12065 -0.3048)
			(end -0.67945 -0.3048)
			(stroke
				(width 0.1)
				(type default)
			)
			(layer "B.Fab")
		)
		(fp_line
			(start -0.67945 -0.3048)
			(end -0.67945 0.3048)
			(stroke
				(width 0.1)
				(type default)
			)
			(layer "B.Fab")
		)
		(fp_line
			(start 0.12065 -0.2794)
			(end -0.12065 -0.2794)
			(stroke
				(width 0.1)
				(type default)
			)
			(layer "B.Fab")
		)
		(fp_line
			(start -0.12065 -0.2794)
			(end -0.12065 -0.3048)
			(stroke
				(width 0.1)
				(type default)
			)
			(layer "B.Fab")
		)
		(fp_line
			(start 0.12065 0.2794)
			(end 0.12065 0.3048)
			(stroke
				(width 0.1)
				(type default)
			)
			(layer "B.Fab")
		)
		(fp_line
			(start -0.120396 0.2794)
			(end 0.12065 0.2794)
			(stroke
				(width 0.1)
				(type default)
			)
			(layer "B.Fab")
		)
		(fp_line
			(start 0.67945 0.3048)
			(end 0.67945 -0.305054)
			(stroke
				(width 0.1)
				(type default)
			)
			(layer "B.Fab")
		)
		(fp_line
			(start 0.12065 0.3048)
			(end 0.67945 0.3048)
			(stroke
				(width 0.1)
				(type default)
			)
			(layer "B.Fab")
		)
		(fp_line
			(start -0.120396 0.3048)
			(end -0.120396 0.2794)
			(stroke
				(width 0.1)
				(type default)
			)
			(layer "B.Fab")
		)
		(fp_line
			(start -0.67945 0.3048)
			(end -0.120396 0.3048)
			(stroke
				(width 0.1)
				(type default)
			)
			(layer "B.Fab")
		)
		(pad "1" smd circle
			(at 0.40005 0 270)
			(size 0 0)
			(layers "B.Cu" "B.Mask" "B.Paste")
			(net "PVDD11_S3_P1")
		)
		(pad "2" smd circle
			(at -0.40005 0 270)
			(size 0 0)
			(layers "B.Cu" "B.Mask" "B.Paste")
			(net "GND")
		)
	)
	(footprint ""
		(layer "B.Cu")
		(at 156.154374 -323.798692)
		(property "Reference" "R562"
			(at 0 0 0)
			(layer "B.SilkS")
			(hide yes)
			(effects
				(font
					(size 1.27 1.27)
				)
				(justify mirror)
			)
		)
		(property "Value" ""
			(at 0 0 0)
			(layer "B.Fab")
			(effects
				(font
					(size 1.27 1.27)
				)
				(justify mirror)
			)
		)
		(duplicate_pad_numbers_are_jumpers no)
		(fp_line
			(start -0.7874 -0.4064)
			(end -0.7874 0.4064)
			(stroke
				(width 0.1524)
				(type default)
			)
			(layer "B.SilkS")
		)
		(fp_line
			(start -0.7874 0.4064)
			(end 0.7874 0.4064)
			(stroke
				(width 0.1524)
				(type default)
			)
			(layer "B.SilkS")
		)
		(fp_line
			(start 0.7874 -0.4064)
			(end -0.7874 -0.4064)
			(stroke
				(width 0.1524)
				(type default)
			)
			(layer "B.SilkS")
		)
		(fp_line
			(start 0.7874 0.4064)
			(end 0.7874 -0.4064)
			(stroke
				(width 0.1524)
				(type default)
			)
			(layer "B.SilkS")
		)
		(fp_line
			(start -0.67945 -0.3048)
			(end -0.67945 0.3048)
			(stroke
				(width 0.1)
				(type default)
			)
			(layer "B.Fab")
		)
		(fp_line
			(start -0.67945 0.3048)
			(end -0.120396 0.3048)
			(stroke
				(width 0.1)
				(type default)
			)
			(layer "B.Fab")
		)
		(fp_line
			(start -0.12065 -0.3048)
			(end -0.67945 -0.3048)
			(stroke
				(width 0.1)
				(type default)
			)
			(layer "B.Fab")
		)
		(fp_line
			(start -0.12065 -0.2794)
			(end -0.12065 -0.3048)
			(stroke
				(width 0.1)
				(type default)
			)
			(layer "B.Fab")
		)
		(fp_line
			(start -0.120396 0.2794)
			(end 0.12065 0.2794)
			(stroke
				(width 0.1)
				(type default)
			)
			(layer "B.Fab")
		)
		(fp_line
			(start -0.120396 0.3048)
			(end -0.120396 0.2794)
			(stroke
				(width 0.1)
				(type default)
			)
			(layer "B.Fab")
		)
		(fp_line
			(start 0.12065 -0.305054)
			(end 0.12065 -0.2794)
			(stroke
				(width 0.1)
				(type default)
			)
			(layer "B.Fab")
		)
		(fp_line
			(start 0.12065 -0.2794)
			(end -0.12065 -0.2794)
			(stroke
				(width 0.1)
				(type default)
			)
			(layer "B.Fab")
		)
		(fp_line
			(start 0.12065 0.2794)
			(end 0.12065 0.3048)
			(stroke
				(width 0.1)
				(type default)
			)
			(layer "B.Fab")
		)
		(fp_line
			(start 0.12065 0.3048)
			(end 0.67945 0.3048)
			(stroke
				(width 0.1)
				(type default)
			)
			(layer "B.Fab")
		)
		(fp_line
			(start 0.67945 -0.305054)
			(end 0.12065 -0.305054)
			(stroke
				(width 0.1)
				(type default)
			)
			(layer "B.Fab")
		)
		(fp_line
			(start 0.67945 0.3048)
			(end 0.67945 -0.305054)
			(stroke
				(width 0.1)
				(type default)
			)
			(layer "B.Fab")
		)
		(pad "1" smd circle
			(at 0.40005 0 180)
			(size 0 0)
			(layers "B.Cu" "B.Mask" "B.Paste")
			(net "PVDD18_S5_P1")
		)
		(pad "2" smd circle
			(at -0.40005 0 180)
			(size 0 0)
			(layers "B.Cu" "B.Mask" "B.Paste")
			(net "CPU1_NMI_SYNC_FLOOD_N")
		)
	)
	(footprint ""
		(layer "B.Cu")
		(at 138.24204 -389.81126)
		(property "Reference" "PJ09_P1_P"
			(at 0 0 0)
			(layer "B.SilkS")
			(hide yes)
			(effects
				(font
					(size 1.27 1.27)
				)
				(justify mirror)
			)
		)
		(property "Value" ""
			(at 0 0 0)
			(layer "B.Fab")
			(effects
				(font
					(size 1.27 1.27)
				)
				(justify mirror)
			)
		)
		(duplicate_pad_numbers_are_jumpers no)
		(zone
			(layer "In15.Cu")
			(hatch none 0.5)
			(connect_pads
				(clearance 0)
			)
			(min_thickness 0.25)
			(keepout
				(tracks allowed)
				(vias not_allowed)
				(pads allowed)
				(copperpour not_allowed)
				(footprints allowed)
			)
			(placement
				(enabled no)
				(sheetname "")
			)
			(fill
				(thermal_gap 0.5)
				(thermal_bridge_width 0.5)
				(island_removal_mode 0)
			)
			(polygon
				(pts
					(xy 138.45794 -389.62076) (xy 138.02614 -389.62076) (xy 138.02614 -390.00176) (xy 138.45794 -390.00176)
				)
			)
		)
	)
)
